# S9S_MB_2U (Grand Teton) — schematic netlist excerpt (pin names and nets, part order shuffled) for the footprints in the layout excerpt that follows; sources: Cadence DE-HDL packaged netlist, KiCad conversion of 03242023_DA0F0TMBIJ0_F0T_Motherboard_J_brd_V01_OCP.brd

PC578_P1_1  Q_CAP  22UF 4V 20% X6S  pkg C0805  page 285 : A = PVCCIN_CPU1 ; B = GND
R836  Q_RES  0 5% CHIP  pkg 0402LF  page 129 : A = RST_PLD_CPU0_DRAM_AB_N ; B = RST_M_AB_CPU0_FPGA_N
PC1751  Q_CAP  1NF 50V 10% EMPTY  pkg 0402  page 304 : A = P12V_HSC_GATE_RC ; B = P12V_HSC_GATE2

(kicad_pcb
	(version 20260206)
	(generator "pcbnew")
	(generator_version "10.0")
	(general
		(thickness 1.6)
		(legacy_teardrops no)
	)
	(paper "A4")
	(title_block
		(title "03242023_DA0F0TMBIJ0_F0T_Motherboard_J_brd_V01_OCP.brd")
		(comment 1 "Grand Teton / footprints 4746-4748 of 6105")
	)
	(layers
		(0 "F.Cu" signal "TOP")
		(4 "In1.Cu" signal "GND")
		(6 "In2.Cu" signal "IN1")
		(8 "In3.Cu" signal "GND1")
		(10 "In4.Cu" signal "IN2")
		(12 "In5.Cu" signal "GND2")
		(14 "In6.Cu" signal "IN3")
		(16 "In7.Cu" signal "GND3")
		(18 "In8.Cu" signal "VCC")
		(20 "In9.Cu" signal "VCC1")
		(22 "In10.Cu" signal "GND4")
		(24 "In11.Cu" signal "IN4")
		(26 "In12.Cu" signal "GND5")
		(28 "In13.Cu" signal "IN5")
		(30 "In14.Cu" signal "GND6")
		(32 "In15.Cu" signal "IN6")
		(34 "In16.Cu" signal "GND7")
		(2 "B.Cu" signal "BOTTOM")
		(9 "F.Adhes" user "F.Adhesive")
		(11 "B.Adhes" user "B.Adhesive")
		(13 "F.Paste" user "Package Geometry/Pastemask Top")
		(15 "B.Paste" user "Package Geometry/Pastemask Bottom")
		(5 "F.SilkS" user "Ref Des/Silkscreen Top")
		(7 "B.SilkS" user "Ref Des/Silkscreen Bottom")
		(1 "F.Mask" user "Board Geometry/Soldermask Top")
		(3 "B.Mask" user "Board Geometry/Soldermask Bottom")
		(17 "Dwgs.User" user "User.Drawings")
		(19 "Cmts.User" user "User.Comments")
		(21 "Eco1.User" user "User.Eco1")
		(23 "Eco2.User" user "User.Eco2")
		(25 "Edge.Cuts" user "Board Geometry/Outline")
		(27 "Margin" user)
		(31 "F.CrtYd" user "Package Geometry/Place Bound Top")
		(29 "B.CrtYd" user "Package Geometry/Place Bound Bottom")
		(35 "F.Fab" user "Ref Des/Assembly Top")
		(33 "B.Fab" user "Ref Des/Assembly Bottom")
	)
	(footprint ""
		(layer "B.Cu")
		(at 97.748598 -324.753986 -90)
		(property "Reference" "PC578_P1_1"
			(at 0 0 90)
			(layer "B.SilkS")
			(hide yes)
			(effects
				(font
					(size 1.27 1.27)
				)
				(justify mirror)
			)
		)
		(property "Value" ""
			(at 0 0 90)
			(layer "B.Fab")
			(effects
				(font
					(size 1.27 1.27)
				)
				(justify mirror)
			)
		)
		(duplicate_pad_numbers_are_jumpers no)
		(fp_line
			(start -1.524 0.762)
			(end 1.524 0.762)
			(stroke
				(width 0.1524)
				(type default)
			)
			(layer "B.SilkS")
		)
		(fp_line
			(start 1.524 0.762)
			(end 1.524 -0.762)
			(stroke
				(width 0.1524)
				(type default)
			)
			(layer "B.SilkS")
		)
		(fp_line
			(start -1.524 -0.762)
			(end -1.524 0.762)
			(stroke
				(width 0.1524)
				(type default)
			)
			(layer "B.SilkS")
		)
		(fp_line
			(start 1.524 -0.762)
			(end -1.524 -0.762)
			(stroke
				(width 0.1524)
				(type default)
			)
			(layer "B.SilkS")
		)
		(fp_line
			(start -1.1049 0.724916)
			(end -1.1049 -0.724916)
			(stroke
				(width 0.1)
				(type default)
			)
			(layer "B.Fab")
		)
		(fp_line
			(start 1.1049 0.724916)
			(end -1.1049 0.724916)
			(stroke
				(width 0.1)
				(type default)
			)
			(layer "B.Fab")
		)
		(fp_line
			(start -1.1049 -0.724916)
			(end 1.1049 -0.724916)
			(stroke
				(width 0.1)
				(type default)
			)
			(layer "B.Fab")
		)
		(fp_line
			(start 1.1049 -0.724916)
			(end 1.1049 0.724916)
			(stroke
				(width 0.1)
				(type default)
			)
			(layer "B.Fab")
		)
		(pad "1" smd rect
			(at 0.889 0 270)
			(size 1.016 1.27)
			(layers "B.Cu" "B.Mask" "B.Paste")
			(net "PVCCIN_CPU1")
		)
		(pad "2" smd rect
			(at -0.889 0 270)
			(size 1.016 1.27)
			(layers "B.Cu" "B.Mask" "B.Paste")
			(net "GND")
		)
	)
	(footprint ""
		(layer "B.Cu")
		(at 285.462726 -193.691256 -90)
		(property "Reference" "R836"
			(at 0 0 90)
			(layer "B.SilkS")
			(hide yes)
			(effects
				(font
					(size 1.27 1.27)
				)
				(justify mirror)
			)
		)
		(property "Value" ""
			(at 0 0 90)
			(layer "B.Fab")
			(effects
				(font
					(size 1.27 1.27)
				)
				(justify mirror)
			)
		)
		(duplicate_pad_numbers_are_jumpers no)
		(fp_line
			(start -0.7874 0.4064)
			(end 0.7874 0.4064)
			(stroke
				(width 0.1524)
				(type default)
			)
			(layer "B.SilkS")
		)
		(fp_line
			(start 0.7874 0.4064)
			(end 0.7874 -0.4064)
			(stroke
				(width 0.1524)
				(type default)
			)
			(layer "B.SilkS")
		)
		(fp_line
			(start -0.7874 -0.4064)
			(end -0.7874 0.4064)
			(stroke
				(width 0.1524)
				(type default)
			)
			(layer "B.SilkS")
		)
		(fp_line
			(start 0.7874 -0.4064)
			(end -0.7874 -0.4064)
			(stroke
				(width 0.1524)
				(type default)
			)
			(layer "B.SilkS")
		)
		(fp_line
			(start -0.67945 0.3048)
			(end -0.120396 0.3048)
			(stroke
				(width 0.1)
				(type default)
			)
			(layer "B.Fab")
		)
		(fp_line
			(start -0.120396 0.3048)
			(end -0.120396 0.2794)
			(stroke
				(width 0.1)
				(type default)
			)
			(layer "B.Fab")
		)
		(fp_line
			(start 0.12065 0.3048)
			(end 0.67945 0.3048)
			(stroke
				(width 0.1)
				(type default)
			)
			(layer "B.Fab")
		)
		(fp_line
			(start 0.67945 0.3048)
			(end 0.67945 -0.305054)
			(stroke
				(width 0.1)
				(type default)
			)
			(layer "B.Fab")
		)
		(fp_line
			(start -0.120396 0.2794)
			(end 0.12065 0.2794)
			(stroke
				(width 0.1)
				(type default)
			)
			(layer "B.Fab")
		)
		(fp_line
			(start 0.12065 0.2794)
			(end 0.12065 0.3048)
			(stroke
				(width 0.1)
				(type default)
			)
			(layer "B.Fab")
		)
		(fp_line
			(start -0.12065 -0.2794)
			(end -0.12065 -0.3048)
			(stroke
				(width 0.1)
				(type default)
			)
			(layer "B.Fab")
		)
		(fp_line
			(start 0.12065 -0.2794)
			(end -0.12065 -0.2794)
			(stroke
				(width 0.1)
				(type default)
			)
			(layer "B.Fab")
		)
		(fp_line
			(start -0.67945 -0.3048)
			(end -0.67945 0.3048)
			(stroke
				(width 0.1)
				(type default)
			)
			(layer "B.Fab")
		)
		(fp_line
			(start -0.12065 -0.3048)
			(end -0.67945 -0.3048)
			(stroke
				(width 0.1)
				(type default)
			)
			(layer "B.Fab")
		)
		(fp_line
			(start 0.12065 -0.305054)
			(end 0.12065 -0.2794)
			(stroke
				(width 0.1)
				(type default)
			)
			(layer "B.Fab")
		)
		(fp_line
			(start 0.67945 -0.305054)
			(end 0.12065 -0.305054)
			(stroke
				(width 0.1)
				(type default)
			)
			(layer "B.Fab")
		)
		(pad "1" smd circle
			(at 0.40005 0 90)
			(size 0 0)
			(layers "B.Cu" "B.Mask" "B.Paste")
			(net "RST_PLD_CPU0_DRAM_AB_N")
		)
		(pad "2" smd circle
			(at -0.40005 0 90)
			(size 0 0)
			(layers "B.Cu" "B.Mask" "B.Paste")
			(net "RST_M_AB_CPU0_FPGA_N")
		)
	)
	(footprint ""
		(layer "B.Cu")
		(at 245.25478 -396.43304 90)
		(property "Reference" "PC1751"
			(at 0 0 90)
			(layer "B.SilkS")
			(hide yes)
			(effects
				(font
					(size 1.27 1.27)
				)
				(justify mirror)
			)
		)
		(property "Value" ""
			(at 0 0 90)
			(layer "B.Fab")
			(effects
				(font
					(size 1.27 1.27)
				)
				(justify mirror)
			)
		)
		(duplicate_pad_numbers_are_jumpers no)
		(fp_line
			(start 0.7874 -0.4064)
			(end -0.7874 -0.4064)
			(stroke
				(width 0.1524)
				(type default)
			)
			(layer "B.SilkS")
		)
		(fp_line
			(start -0.7874 -0.4064)
			(end -0.7874 0.4064)
			(stroke
				(width 0.1524)
				(type default)
			)
			(layer "B.SilkS")
		)
		(fp_line
			(start 0.7874 0.4064)
			(end 0.7874 -0.4064)
			(stroke
				(width 0.1524)
				(type default)
			)
			(layer "B.SilkS")
		)
		(fp_line
			(start -0.7874 0.4064)
			(end 0.7874 0.4064)
			(stroke
				(width 0.1524)
				(type default)
			)
			(layer "B.SilkS")
		)
		(fp_line
			(start 0.67945 -0.305054)
			(end 0.12065 -0.305054)
			(stroke
				(width 0.1)
				(type default)
			)
			(layer "B.Fab")
		)
		(fp_line
			(start 0.12065 -0.305054)
			(end 0.12065 -0.2794)
			(stroke
				(width 0.1)
				(type default)
			)
			(layer "B.Fab")
		)
		(fp_line
			(start -0.12065 -0.3048)
			(end -0.67945 -0.3048)
			(stroke
				(width 0.1)
				(type default)
			)
			(layer "B.Fab")
		)
		(fp_line
			(start -0.67945 -0.3048)
			(end -0.67945 0.3048)
			(stroke
				(width 0.1)
				(type default)
			)
			(layer "B.Fab")
		)
		(fp_line
			(start 0.12065 -0.2794)
			(end -0.12065 -0.2794)
			(stroke
				(width 0.1)
				(type default)
			)
			(layer "B.Fab")
		)
		(fp_line
			(start -0.12065 -0.2794)
			(end -0.12065 -0.3048)
			(stroke
				(width 0.1)
				(type default)
			)
			(layer "B.Fab")
		)
		(fp_line
			(start 0.12065 0.2794)
			(end 0.12065 0.3048)
			(stroke
				(width 0.1)
				(type default)
			)
			(layer "B.Fab")
		)
		(fp_line
			(start -0.120396 0.2794)
			(end 0.12065 0.2794)
			(stroke
				(width 0.1)
				(type default)
			)
			(layer "B.Fab")
		)
		(fp_line
			(start 0.67945 0.3048)
			(end 0.67945 -0.305054)
			(stroke
				(width 0.1)
				(type default)
			)
			(layer "B.Fab")
		)
		(fp_line
			(start 0.12065 0.3048)
			(end 0.67945 0.3048)
			(stroke
				(width 0.1)
				(type default)
			)
			(layer "B.Fab")
		)
		(fp_line
			(start -0.120396 0.3048)
			(end -0.120396 0.2794)
			(stroke
				(width 0.1)
				(type default)
			)
			(layer "B.Fab")
		)
		(fp_line
			(start -0.67945 0.3048)
			(end -0.120396 0.3048)
			(stroke
				(width 0.1)
				(type default)
			)
			(layer "B.Fab")
		)
		(pad "1" smd circle
			(at 0.40005 0 270)
			(size 0 0)
			(layers "B.Cu" "B.Mask" "B.Paste")
			(net "P12V_HSC_GATE_RC")
		)
		(pad "2" smd circle
			(at -0.40005 0 270)
			(size 0 0)
			(layers "B.Cu" "B.Mask" "B.Paste")
			(net "P12V_HSC_GATE2")
		)
	)
)
